# S9S_MB_2U (Grand Teton) — schematic netlist excerpt (pin names and nets, part order shuffled) for the footprints in the layout excerpt that follows; sources: Cadence DE-HDL packaged netlist, KiCad conversion of 03242023_DA0F0TMBIJ0_F0T_Motherboard_J_brd_V01_OCP.brd

J26  SCONN288_ADR50017P087CC  SCONN288_ADR50017-P087CC IO  pkg DDR288S_1-1VXB  page 107
  VIN_BULK0  = P12V_S3_AUX_CPU1_NVDIMM
  RFU0  = TP_CHE_CPU1_DIMM2_FRU_0
  VIN_MGMT  = P3V3_AUX
  HSCL  = I3C_SPD_DDREFGH_CPU1_LVC1_SCL_1
  HSDA  = I3C_SPD_DDREFGH_CPU1_LVC1_SDA
  VSS0  = GND
  DQ0_A  = M_E_CPU1_SA_DQ<0>
  VSS1  = GND
  DQ1_A  = M_E_CPU1_SA_DQ<1>
  VSS2  = GND
  DQS0_A_T  = M_E_CPU1_SA_DQS_DP<0>
  DQS0_A_C  = M_E_CPU1_SA_DQS_DN<0>
  VSS3  = GND
  DQ4_A  = M_E_CPU1_SA_DQ<4>
  VSS4  = GND
  DQ5_A  = M_E_CPU1_SA_DQ<5>
  VSS5  = GND
  DQ8_A  = M_E_CPU1_SA_DQ<8>
  VSS6  = GND
  DQ9_A  = M_E_CPU1_SA_DQ<9>
  VSS7  = GND
  DQS1_A_T  = M_E_CPU1_SA_DQS_DP<1>
  DQS1_A_C  = M_E_CPU1_SA_DQS_DN<1>
  VSS8  = GND
  DQ12_A  = M_E_CPU1_SA_DQ<12>
  VSS9  = GND
  DQ13_A  = M_E_CPU1_SA_DQ<13>
  VSS10  = GND
  DQ16_A  = M_E_CPU1_SA_DQ<16>
  VSS11  = GND
  DQ17_A  = M_E_CPU1_SA_DQ<17>
  VSS12  = GND
  DQS2_A_T  = M_E_CPU1_SA_DQS_DP<2>
  DQS2_A_C  = M_E_CPU1_SA_DQS_DN<2>
  VSS13  = GND
  DQ20_A  = M_E_CPU1_SA_DQ<20>
  VSS14  = GND
  DQ21_A  = M_E_CPU1_SA_DQ<21>
  VSS15  = GND
  DQ24_A  = M_E_CPU1_SA_DQ<24>
  VSS16  = GND
  DQ25_A  = M_E_CPU1_SA_DQ<25>
  VSS17  = GND
  DQS3_A_T  = M_E_CPU1_SA_DQS_DP<3>
  DQS3_A_C  = M_E_CPU1_SA_DQS_DN<3>
  VSS18  = GND
  DQ28_A  = M_E_CPU1_SA_DQ<28>
  VSS19  = GND
  DQ29_A  = M_E_CPU1_SA_DQ<29>
  VSS20  = GND
  CB0_A  = M_E_CPU1_SA_CB<0>
  VSS21  = GND
  CB1_A  = M_E_CPU1_SA_CB<1>
  VSS22  = GND
  DQS4_A_T  = M_E_CPU1_SA_DQS_DP<4>
  DQS4_A_C  = M_E_CPU1_SA_DQS_DN<4>
  VSS23  = GND
  CB4_A  = M_E_CPU1_SA_CB<4>
  VSS24  = GND
  CB5_A  = M_E_CPU1_SA_CB<5>
  VSS25  = GND
  ALERT_N  = M_E_CPU1_ALERT_N
  VSS26  = GND
  CS0_A_N  = M_E_CPU1_SA_CS_N<2>
  VSS27  = GND
  CA0_A  = M_E_CPU1_SA_CA<0>
  VSS28  = GND
  CA2_A  = M_E_CPU1_SA_CA<2>
  VSS29  = GND
  CA4_A  = M_E_CPU1_SA_CA<4>
  VSS30  = GND
  CA6_A  = M_E_CPU1_SA_CA<6>
  VSS31  = GND
  PAR_A  = M_E_CPU1_SA_PAR
  VSS32  = GND
  CA0_B  = M_E_CPU1_SB_CA<0>
  VSS33  = GND
  CA2_B  = M_E_CPU1_SB_CA<2>
  VSS34  = GND
  CA4_B  = M_E_CPU1_SB_CA<4>
  VSS35  = GND
  CA6_B  = M_E_CPU1_SB_CA<6>
  VSS36  = GND
  CS0_B_N  = M_E_CPU1_SB_CS_N<2>
  VSS37  = GND
  \lbd||rsp_a_n\  = M_E_CPU1_SA_RSP<1>
  \lbs||rsp_b_n\  = M_E_CPU1_SB_RSP<1>
  VSS38  = GND
  CB4_B  = M_E_CPU1_SB_CB<4>
  VSS39  = GND
  CB5_B  = M_E_CPU1_SB_CB<5>
  VSS40  = GND
  \dqs9_b_t||tdqs9_b_t||dbi4_b_n\  = M_E_CPU1_SB_DQS_DP<9>
  \dqs9_b_c||tdqs9_b_c\  = M_E_CPU1_SB_DQS_DN<9>
  VSS41  = GND
  CB0_B  = M_E_CPU1_SB_CB<0>
  VSS42  = GND
  CB1_B  = M_E_CPU1_SB_CB<1>
  VSS43  = GND
  DQ0_B  = M_E_CPU1_SB_DQ<0>
  VSS44  = GND
  DQ1_B  = M_E_CPU1_SB_DQ<1>
  VSS45  = GND
  DQS0_B_T  = M_E_CPU1_SB_DQS_DP<0>
  DQS0_B_C  = M_E_CPU1_SB_DQS_DN<0>
  VSS46  = GND
  DQ4_B  = M_E_CPU1_SB_DQ<4>
  VSS47  = GND
  DQ5_B  = M_E_CPU1_SB_DQ<5>
  VSS48  = GND
  DQ8_B  = M_E_CPU1_SB_DQ<8>
  VSS49  = GND
  DQ9_B  = M_E_CPU1_SB_DQ<9>
  VSS50  = GND
  DQS1_B_T  = M_E_CPU1_SB_DQS_DP<1>
  DQS1_B_C  = M_E_CPU1_SB_DQS_DN<1>
  VSS51  = GND
  DQ12_B  = M_E_CPU1_SB_DQ<12>
  VSS52  = GND
  DQ13_B  = M_E_CPU1_SB_DQ<13>
  VSS53  = GND
  DQ16_B  = M_E_CPU1_SB_DQ<16>
  VSS54  = GND
  DQ17_B  = M_E_CPU1_SB_DQ<17>
  VSS55  = GND
  DQS2_B_T  = M_E_CPU1_SB_DQS_DP<2>
  DQS2_B_C  = M_E_CPU1_SB_DQS_DN<2>
  VSS56  = GND
  DQ20_B  = M_E_CPU1_SB_DQ<20>
  VSS57  = GND
  DQ21_B  = M_E_CPU1_SB_DQ<21>
  VSS58  = GND
  DQ24_B  = M_E_CPU1_SB_DQ<24>
  VSS59  = GND
  DQ25_B  = M_E_CPU1_SB_DQ<25>
  VSS60  = GND
  DQS3_B_T  = M_E_CPU1_SB_DQS_DP<3>
  DQS3_B_C  = M_E_CPU1_SB_DQS_DN<3>
  VSS61  = GND
  DQ28_B  = M_E_CPU1_SB_DQ<28>
  VSS62  = GND
  DQ29_B  = M_E_CPU1_SB_DQ<29>
  VSS63  = GND
  RFU1  = TP_CHE_CPU1_DIMM2_FRU_1
  VIN_BULK1  = P12V_S3_AUX_CPU1_NVDIMM
  VIN_BULK2  = P12V_S3_AUX_CPU1_NVDIMM
  \pwr_good||fail_n\  = PWRGD_CHE_CPU1_DIMM2
  HSA  = PD_CHE_CPU1_DIMM2_SAA
  RFU2  = TP_CHE_CPU1_DIMM2_FRU_2
  RFU3  = TP_CHE_CPU1_DIMM2_FRU_3
  VSS64  = GND
  DQ2_A  = M_E_CPU1_SA_DQ<2>
  VSS65  = GND
  DQ3_A  = M_E_CPU1_SA_DQ<3>
  VSS66  = GND
  \dqs5_a_c||tdqs5_a_c||dqs5_a_t||tdqs5_a_t\  = M_E_CPU1_SA_DQS_DN<5>
  \dqs5_a_t||tdqs5_a_t\  = M_E_CPU1_SA_DQS_DP<5>
  VSS67  = GND
  DQ6_A  = M_E_CPU1_SA_DQ<6>
  VSS68  = GND
  DQ7_A  = M_E_CPU1_SA_DQ<7>
  VSS69  = GND
  DQ10_A  = M_E_CPU1_SA_DQ<10>
  VSS70  = GND
  DQ11_A  = M_E_CPU1_SA_DQ<11>
  VSS71  = GND
  \dqs6_a_c||tdqs6_a_c||dqs6_a_t||tdqs6_a_t\  = M_E_CPU1_SA_DQS_DN<6>
  \dqs6_a_t||tdqs6_a_t\  = M_E_CPU1_SA_DQS_DP<6>
  VSS72  = GND
  DQ14_A  = M_E_CPU1_SA_DQ<14>
  VSS73  = GND
  DQ15_A  = M_E_CPU1_SA_DQ<15>
  VSS74  = GND
  DQ18_A  = M_E_CPU1_SA_DQ<18>
  VSS75  = GND
  DQ19_A  = M_E_CPU1_SA_DQ<19>
  VSS76  = GND
  \dqs7_a_c||tdqs7_a_c\  = M_E_CPU1_SA_DQS_DN<7>
  \dqs7_a_t||tdqs7_a_t\  = M_E_CPU1_SA_DQS_DP<7>
  VSS77  = GND
  DQ22_A  = M_E_CPU1_SA_DQ<22>
  VSS78  = GND
  DQ23_A  = M_E_CPU1_SA_DQ<23>
  VSS79  = GND
  DQ26_A  = M_E_CPU1_SA_DQ<26>
  VSS80  = GND
  DQ27_A  = M_E_CPU1_SA_DQ<27>
  VSS81  = GND
  \dqs8_a_c||tdqs8_a_c\  = M_E_CPU1_SA_DQS_DN<8>
  \dqs8_a_t||tdqs8_a_t\  = M_E_CPU1_SA_DQS_DP<8>
  VSS82  = GND
  DQ30_A  = M_E_CPU1_SA_DQ<30>
  VSS83  = GND
  DQ31_A  = M_E_CPU1_SA_DQ<31>
  VSS84  = GND
  CB2_A  = M_E_CPU1_SA_CB<2>
  VSS85  = GND
  CB3_A  = M_E_CPU1_SA_CB<3>
  VSS86  = GND
  \dqs9_a_c||tdqs9_a_c\  = M_E_CPU1_SA_DQS_DN<9>
  \dqs9_a_t||tdqs9_a_t\  = M_E_CPU1_SA_DQS_DP<9>
  VSS87  = GND
  CB6_A  = M_E_CPU1_SA_CB<6>
  VSS88  = GND
  CB7_A  = M_E_CPU1_SA_CB<7>
  VSS89  = GND
  RESET_N  = RST_M_EF_CPU1_FPGA_N
  VSS90  = GND
  CS1_A_N  = M_E_CPU1_SA_CS_N<3>
  VSS91  = GND
  CA1_A  = M_E_CPU1_SA_CA<1>
  VSS92  = GND
  CA3_A  = M_E_CPU1_SA_CA<3>
  VSS93  = GND
  CA5_A  = M_E_CPU1_SA_CA<5>
  VSS94  = GND
  CK_T  = M_E_CPU1_CLK_DP<1>
  CK_C  = M_E_CPU1_CLK_DN<1>
  VSS95  = GND
  RFU4  = TP_CHE_CPU1_DIMM2_FRU_4
  CA1_B  = M_E_CPU1_SB_CA<1>
  VSS96  = GND
  CA3_B  = M_E_CPU1_SB_CA<3>
  VSS97  = GND
  CA5_B  = M_E_CPU1_SB_CA<5>
  VSS98  = GND
  PAR_B  = M_E_CPU1_SB_PAR
  VSS99  = GND
  CS1_B_N  = M_E_CPU1_SB_CS_N<3>
  VSS100  = GND
  RFU5  = TP_CHE_CPU1_DIMM2_FRU_5
  RFU6  = TP_CHE_CPU1_DIMM2_FRU_6
  VSS101  = GND
  CB6_B  = M_E_CPU1_SB_CB<6>
  VSS102  = GND
  CB7_B  = M_E_CPU1_SB_CB<7>
  VSS103  = GND
  DQS4_B_C  = M_E_CPU1_SB_DQS_DN<4>
  DQS4_B_T  = M_E_CPU1_SB_DQS_DP<4>
  VSS104  = GND
  CB2_B  = M_E_CPU1_SB_CB<2>
  VSS105  = GND
  CB3_B  = M_E_CPU1_SB_CB<3>
  VSS106  = GND
  DQ2_B  = M_E_CPU1_SB_DQ<2>
  VSS107  = GND
  DQ3_B  = M_E_CPU1_SB_DQ<3>
  VSS108  = GND
  \dqs5_b_c||tdqs5_b_c\  = M_E_CPU1_SB_DQS_DN<5>
  \dqs5_b_t||tdqs5_b_t\  = M_E_CPU1_SB_DQS_DP<5>
  VSS109  = GND
  DQ6_B  = M_E_CPU1_SB_DQ<6>
  VSS110  = GND
  DQ7_B  = M_E_CPU1_SB_DQ<7>
  VSS111  = GND
  DQ10_B  = M_E_CPU1_SB_DQ<10>
  VSS112  = GND
  DQ11_B  = M_E_CPU1_SB_DQ<11>
  VSS113  = GND
  \dqs6_b_c||tdqs6_b_c\  = M_E_CPU1_SB_DQS_DN<6>
  \dqs6_b_t||tdqs6_b_t\  = M_E_CPU1_SB_DQS_DP<6>
  VSS114  = GND
  DQ14_B  = M_E_CPU1_SB_DQ<14>
  VSS115  = GND
  DQ15_B  = M_E_CPU1_SB_DQ<15>
  VSS116  = GND
  DQ18_B  = M_E_CPU1_SB_DQ<18>
  VSS117  = GND
  DQ19_B  = M_E_CPU1_SB_DQ<19>
  VSS118  = GND
  \dqs7_b_c||tdqs7_b_c\  = M_E_CPU1_SB_DQS_DN<7>
  \dqs7_b_t||tdqs7_b_t\  = M_E_CPU1_SB_DQS_DP<7>
  VSS119  = GND
  DQ22_B  = M_E_CPU1_SB_DQ<22>
  VSS120  = GND
  DQ23_B  = M_E_CPU1_SB_DQ<23>
  VSS121  = GND
  DQ26_B  = M_E_CPU1_SB_DQ<26>
  VSS122  = GND
  DQ27_B  = M_E_CPU1_SB_DQ<27>
  VSS123  = GND
  \dqs8_b_c||tdqs8_b_c\  = M_E_CPU1_SB_DQS_DN<8>
  \dqs8_b_t||tdqs8_b_t\  = M_E_CPU1_SB_DQS_DP<8>
  VSS124  = GND
  DQ30_B  = M_E_CPU1_SB_DQ<30>
  VSS125  = GND
  DQ31_B  = M_E_CPU1_SB_DQ<31>
  VSS126  = GND
  G1  = GND
  G2  = GND
  G3  = GND

(kicad_pcb
	(version 20260206)
	(generator "pcbnew")
	(generator_version "10.0")
	(general
		(thickness 1.6)
		(legacy_teardrops no)
	)
	(paper "A4")
	(title_block
		(title "03242023_DA0F0TMBIJ0_F0T_Motherboard_J_brd_V01_OCP.brd")
		(comment 1 "Grand Teton / footprint 1065 of 6105 (J26), pads 92-137 of 291")
	)
	(layers
		(0 "F.Cu" signal "TOP")
		(4 "In1.Cu" signal "GND")
		(6 "In2.Cu" signal "IN1")
		(8 "In3.Cu" signal "GND1")
		(10 "In4.Cu" signal "IN2")
		(12 "In5.Cu" signal "GND2")
		(14 "In6.Cu" signal "IN3")
		(16 "In7.Cu" signal "GND3")
		(18 "In8.Cu" signal "VCC")
		(20 "In9.Cu" signal "VCC1")
		(22 "In10.Cu" signal "GND4")
		(24 "In11.Cu" signal "IN4")
		(26 "In12.Cu" signal "GND5")
		(28 "In13.Cu" signal "IN5")
		(30 "In14.Cu" signal "GND6")
		(32 "In15.Cu" signal "IN6")
		(34 "In16.Cu" signal "GND7")
		(2 "B.Cu" signal "BOTTOM")
		(9 "F.Adhes" user "F.Adhesive")
		(11 "B.Adhes" user "B.Adhesive")
		(13 "F.Paste" user "Package Geometry/Pastemask Top")
		(15 "B.Paste" user "Package Geometry/Pastemask Bottom")
		(5 "F.SilkS" user "Ref Des/Silkscreen Top")
		(7 "B.SilkS" user "Ref Des/Silkscreen Bottom")
		(1 "F.Mask" user "Board Geometry/Soldermask Top")
		(3 "B.Mask" user "Board Geometry/Soldermask Bottom")
		(17 "Dwgs.User" user "User.Drawings")
		(19 "Cmts.User" user "User.Comments")
		(21 "Eco1.User" user "User.Eco1")
		(23 "Eco2.User" user "User.Eco2")
		(25 "Edge.Cuts" user "Board Geometry/Outline")
		(27 "Margin" user)
		(31 "F.CrtYd" user "Package Geometry/Place Bound Top")
		(29 "B.CrtYd" user "Package Geometry/Place Bound Bottom")
		(35 "F.Fab" user "Ref Des/Assembly Top")
		(33 "B.Fab" user "Ref Des/Assembly Bottom")
	)
	(footprint ""
		(layer "F.Cu")
		(at 160.86328 -258.091686)
		(property "Reference" "J26"
			(at -3.683 -81.702148 0)
			(unlocked yes)
			(layer "F.SilkS")
			(effects
				(font
					(size 0.7874 0.5842)
					(thickness 0.1524)
				)
				(justify left)
			)
		)
		(property "Value" ""
			(at 0 0 0)
			(layer "F.Fab")
			(effects
				(font
					(size 1.27 1.27)
				)
			)
		)
		(duplicate_pad_numbers_are_jumpers no)
		(pad "92" smd rect
			(at -2.050034 19.12493 270)
			(size 0.519938 1.4986)
			(layers "F.Cu" "F.Mask" "F.Paste")
			(net "GND")
		)
		(pad "93" smd rect
			(at -2.050034 19.975068 270)
			(size 0.519938 1.4986)
			(layers "F.Cu" "F.Mask" "F.Paste")
			(net "M_E_CPU1_SB_DQS_DP<9>")
		)
		(pad "94" smd rect
			(at -2.050034 20.824952 270)
			(size 0.519938 1.4986)
			(layers "F.Cu" "F.Mask" "F.Paste")
			(net "M_E_CPU1_SB_DQS_DN<9>")
		)
		(pad "95" smd rect
			(at -2.050034 21.67509 270)
			(size 0.519938 1.4986)
			(layers "F.Cu" "F.Mask" "F.Paste")
			(net "GND")
		)
		(pad "96" smd rect
			(at -2.050034 22.524974 270)
			(size 0.519938 1.4986)
			(layers "F.Cu" "F.Mask" "F.Paste")
			(net "M_E_CPU1_SB_CB<0>")
		)
		(pad "97" smd rect
			(at -2.050034 23.375112 270)
			(size 0.519938 1.4986)
			(layers "F.Cu" "F.Mask" "F.Paste")
			(net "GND")
		)
		(pad "98" smd rect
			(at -2.050034 24.224996 270)
			(size 0.519938 1.4986)
			(layers "F.Cu" "F.Mask" "F.Paste")
			(net "M_E_CPU1_SB_CB<1>")
		)
		(pad "99" smd rect
			(at -2.050034 25.07488 270)
			(size 0.519938 1.4986)
			(layers "F.Cu" "F.Mask" "F.Paste")
			(net "GND")
		)
		(pad "100" smd rect
			(at -2.050034 25.925018 270)
			(size 0.519938 1.4986)
			(layers "F.Cu" "F.Mask" "F.Paste")
			(net "M_E_CPU1_SB_DQ<0>")
		)
		(pad "101" smd rect
			(at -2.050034 26.774902 270)
			(size 0.519938 1.4986)
			(layers "F.Cu" "F.Mask" "F.Paste")
			(net "GND")
		)
		(pad "102" smd rect
			(at -2.050034 27.62504 270)
			(size 0.519938 1.4986)
			(layers "F.Cu" "F.Mask" "F.Paste")
			(net "M_E_CPU1_SB_DQ<1>")
		)
		(pad "103" smd rect
			(at -2.050034 28.474924 270)
			(size 0.519938 1.4986)
			(layers "F.Cu" "F.Mask" "F.Paste")
			(net "GND")
		)
		(pad "104" smd rect
			(at -2.050034 29.325062 270)
			(size 0.519938 1.4986)
			(layers "F.Cu" "F.Mask" "F.Paste")
			(net "M_E_CPU1_SB_DQS_DP<0>")
		)
		(pad "105" smd rect
			(at -2.050034 30.174946 270)
			(size 0.519938 1.4986)
			(layers "F.Cu" "F.Mask" "F.Paste")
			(net "M_E_CPU1_SB_DQS_DN<0>")
		)
		(pad "106" smd rect
			(at -2.050034 31.025084 270)
			(size 0.519938 1.4986)
			(layers "F.Cu" "F.Mask" "F.Paste")
			(net "GND")
		)
		(pad "107" smd rect
			(at -2.050034 31.874968 270)
			(size 0.519938 1.4986)
			(layers "F.Cu" "F.Mask" "F.Paste")
			(net "M_E_CPU1_SB_DQ<4>")
		)
		(pad "108" smd rect
			(at -2.050034 32.725106 270)
			(size 0.519938 1.4986)
			(layers "F.Cu" "F.Mask" "F.Paste")
			(net "GND")
		)
		(pad "109" smd rect
			(at -2.050034 33.57499 270)
			(size 0.519938 1.4986)
			(layers "F.Cu" "F.Mask" "F.Paste")
			(net "M_E_CPU1_SB_DQ<5>")
		)
		(pad "110" smd rect
			(at -2.050034 34.425128 270)
			(size 0.519938 1.4986)
			(layers "F.Cu" "F.Mask" "F.Paste")
			(net "GND")
		)
		(pad "111" smd rect
			(at -2.050034 35.275012 270)
			(size 0.519938 1.4986)
			(layers "F.Cu" "F.Mask" "F.Paste")
			(net "M_E_CPU1_SB_DQ<8>")
		)
		(pad "112" smd rect
			(at -2.050034 36.124896 270)
			(size 0.519938 1.4986)
			(layers "F.Cu" "F.Mask" "F.Paste")
			(net "GND")
		)
		(pad "113" smd rect
			(at -2.050034 36.975034 270)
			(size 0.519938 1.4986)
			(layers "F.Cu" "F.Mask" "F.Paste")
			(net "M_E_CPU1_SB_DQ<9>")
		)
		(pad "114" smd rect
			(at -2.050034 37.824918 270)
			(size 0.519938 1.4986)
			(layers "F.Cu" "F.Mask" "F.Paste")
			(net "GND")
		)
		(pad "115" smd rect
			(at -2.050034 38.675056 270)
			(size 0.519938 1.4986)
			(layers "F.Cu" "F.Mask" "F.Paste")
			(net "M_E_CPU1_SB_DQS_DP<1>")
		)
		(pad "116" smd rect
			(at -2.050034 39.52494 270)
			(size 0.519938 1.4986)
			(layers "F.Cu" "F.Mask" "F.Paste")
			(net "M_E_CPU1_SB_DQS_DN<1>")
		)
		(pad "117" smd rect
			(at -2.050034 40.375078 270)
			(size 0.519938 1.4986)
			(layers "F.Cu" "F.Mask" "F.Paste")
			(net "GND")
		)
		(pad "118" smd rect
			(at -2.050034 41.224962 270)
			(size 0.519938 1.4986)
			(layers "F.Cu" "F.Mask" "F.Paste")
			(net "M_E_CPU1_SB_DQ<12>")
		)
		(pad "119" smd rect
			(at -2.050034 42.0751 270)
			(size 0.519938 1.4986)
			(layers "F.Cu" "F.Mask" "F.Paste")
			(net "GND")
		)
		(pad "120" smd rect
			(at -2.050034 42.924984 270)
			(size 0.519938 1.4986)
			(layers "F.Cu" "F.Mask" "F.Paste")
			(net "M_E_CPU1_SB_DQ<13>")
		)
		(pad "121" smd rect
			(at -2.050034 43.775122 270)
			(size 0.519938 1.4986)
			(layers "F.Cu" "F.Mask" "F.Paste")
			(net "GND")
		)
		(pad "122" smd rect
			(at -2.050034 44.625006 270)
			(size 0.519938 1.4986)
			(layers "F.Cu" "F.Mask" "F.Paste")
			(net "M_E_CPU1_SB_DQ<16>")
		)
		(pad "123" smd rect
			(at -2.050034 45.47489 270)
			(size 0.519938 1.4986)
			(layers "F.Cu" "F.Mask" "F.Paste")
			(net "GND")
		)
		(pad "124" smd rect
			(at -2.050034 46.325028 270)
			(size 0.519938 1.4986)
			(layers "F.Cu" "F.Mask" "F.Paste")
			(net "M_E_CPU1_SB_DQ<17>")
		)
		(pad "125" smd rect
			(at -2.050034 47.174912 270)
			(size 0.519938 1.4986)
			(layers "F.Cu" "F.Mask" "F.Paste")
			(net "GND")
		)
		(pad "126" smd rect
			(at -2.050034 48.02505 270)
			(size 0.519938 1.4986)
			(layers "F.Cu" "F.Mask" "F.Paste")
			(net "M_E_CPU1_SB_DQS_DP<2>")
		)
		(pad "127" smd rect
			(at -2.050034 48.874934 270)
			(size 0.519938 1.4986)
			(layers "F.Cu" "F.Mask" "F.Paste")
			(net "M_E_CPU1_SB_DQS_DN<2>")
		)
		(pad "128" smd rect
			(at -2.050034 49.725072 270)
			(size 0.519938 1.4986)
			(layers "F.Cu" "F.Mask" "F.Paste")
			(net "GND")
		)
		(pad "129" smd rect
			(at -2.050034 50.574956 270)
			(size 0.519938 1.4986)
			(layers "F.Cu" "F.Mask" "F.Paste")
			(net "M_E_CPU1_SB_DQ<20>")
		)
		(pad "130" smd rect
			(at -2.050034 51.425094 270)
			(size 0.519938 1.4986)
			(layers "F.Cu" "F.Mask" "F.Paste")
			(net "GND")
		)
		(pad "131" smd rect
			(at -2.050034 52.274978 270)
			(size 0.519938 1.4986)
			(layers "F.Cu" "F.Mask" "F.Paste")
			(net "M_E_CPU1_SB_DQ<21>")
		)
		(pad "132" smd rect
			(at -2.050034 53.125116 270)
			(size 0.519938 1.4986)
			(layers "F.Cu" "F.Mask" "F.Paste")
			(net "GND")
		)
		(pad "133" smd rect
			(at -2.050034 53.975 270)
			(size 0.519938 1.4986)
			(layers "F.Cu" "F.Mask" "F.Paste")
			(net "M_E_CPU1_SB_DQ<24>")
		)
		(pad "134" smd rect
			(at -2.050034 54.824884 270)
			(size 0.519938 1.4986)
			(layers "F.Cu" "F.Mask" "F.Paste")
			(net "GND")
		)
		(pad "135" smd rect
			(at -2.050034 55.675022 270)
			(size 0.519938 1.4986)
			(layers "F.Cu" "F.Mask" "F.Paste")
			(net "M_E_CPU1_SB_DQ<25>")
		)
		(pad "136" smd rect
			(at -2.050034 56.524906 270)
			(size 0.519938 1.4986)
			(layers "F.Cu" "F.Mask" "F.Paste")
			(net "GND")
		)
		(pad "137" smd rect
			(at -2.050034 57.375044 270)
			(size 0.519938 1.4986)
			(layers "F.Cu" "F.Mask" "F.Paste")
			(net "M_E_CPU1_SB_DQS_DP<3>")
		)
	)
)
